 
. 
 
 
OCP-TAP  
Large Oscillator Form-Factor  
(LOF) 
 
Version 0.1 
 
Hardware Specification 
 
 
Author: <name>



Open Compute Project   •   TAP Large Oscillator Form-Factor (LOF) 
Date:  January 2023         Page 2 
 
Table of Contents 
1. Overview .................................................................................................................................. 3 
1.1. Acronyms.......................................................................................................................... 4 
2. Scope ....................................................................................................................................... 4 
3. License..................................................................................................................................... 5 
3.1. Open Web Foundation (OWF) CLA ................................................................................. 5 
3.2. Acknowledgements .......................................................................................................... 5 
4. Compliance with OCP Tenets ................................................................................................. 7 
4.1. Openness ......................................................................................................................... 7 
4.2. Efficiency .......................................................................................................................... 7 
4.3. Impact ............................................................................................................................... 7 
4.4. Scale ................................................................................................................................. 7 
5. Physical Specifications ............................................................................................................ 8 
5.1. Labeling ............................................................................................................................ 8 
5.2. I/O ..................................................................................................................................... 8 
5.3. Foot Print and Layout ....................................................................................................... 8 
5.3.1. Bottom View .................................................................................................................. 9 
5.3.2. Side View ...................................................................................................................... 9 
6. Hardware Management ........................................................................................................... 9 
7. Version Table ........................................................................................................................... 9 
8. References ............................................................................................................................ 10 
Appendix A  - Checklist  for IC approval  of this Specification (to be completed by contributor(s) 
of this Spec) .................................................................................................................................. 11 
Appendix B-__ <supplier name>  - OCP Supplier Information and Hardware Product 
Recognition Checklist ................................................................................................................... 12 
Appendix C -  Contribution Process FAQs ................................................................................... 14 
 
 
  



Open Compute Project   •   TAP Large Oscillator Form-Factor (LOF) 
Date:  January 2023         Page 3 
1. Overview 
The Large Oscillator Form-Factor (LOF) module is a source of stable output frequency to the 
Time Card.  
This stable frequency also provides Time Cards a holdover reference when GNSS is denied.  
 
The OCP-TAP LOF standardizes the dimensions, layout and connectivity of modular LOF for 
OCP-TAP Time Cards. 
 
A standard modular LOF allows Time Card customers to interchange and upgrade Oscillators 
with ease, and lets manufacturers an easier path to release new and improved holdover and 
stability mechanism compatible with OCP-TAP Time Cards.  
 
The LOF can lead to a faster pace of innovation and development as manufacturers can focus 
on creating new components rather than iterating on the Time Servers, Time Cards and NICs 
for each new product or revision.  
 
 
Figure 1 - Time-Card with LOF 


Open Compute Project   •   TAP Large Oscillator Form-Factor (LOF) 
Date:  January 2023         Page 4 
 
Figure 2 – Zoom-In View of LOF 
1.1. Acronyms  
Abbreviation Definition  
LOF Large Oscillator Form-Factor 
NIC Network Interface Card 
PPS  Pulse Per Second 
PTP  Precision Time Protocol  
RCB Receiver Carrier Board 
TAP Time Appliance Project 
 
2. Scope 
This document defines the technical details for base specification for Large Oscillator Form-
Factor (LOF).    
Any supplier seeking OCP recognition for a hardware product based on this Specification must 
be 100% compliant with all features or requirements described  


Open Compute Project   •   TAP Large Oscillator Form-Factor (LOF) 
Date:  January 2023         Page 5 
3. License 
3.1. Open Web Foundation (OWF) CLA 
Contributions to this Specification are made under the terms and conditions set forth in Open 
Web Foundation Modified Contributor License Agreement (“OWF CLA 1.0”) (“Contribution 
License”) by:  
Meta, NVIDIA 
 
Usage of this Specification is governed by the terms and conditions set forth in Open Web 
Foundation Modified Final Specification Agreement (“OWFa 1.0”) (“Specification 
License”).    
 
You can review the applicable OWFa1.0 Specification License(s) referenced above by the 
contributors to this Specification on the OCP website at 
http://www.opencompute.org/participate/legal-documents/. For actual executed copies of either 
agreement, please contact OCP directly. 
 
 Notes:  
 
1. The above license does not apply to the Appendix or Appendices. The information in the 
Appendix or Appendices is for reference only and non-normative in nature.  
 
NOTWITHSTANDING THE FOREGOING LICENSES, THIS SPECIFICATION IS PROVIDED 
BY OCP "AS IS" AND OCP EXPRESSLY DISCLAIMS ANY WARRANTIES (EXPRESS, 
IMPLIED, OR OTHERWISE), INCLUDING IMPLIED WARRANTIES OF MERCHANTABILITY, 
NON-INFRINGEMENT, FITNESS FOR A PARTICULAR PURPOSE, OR TITLE, RELATED TO 
THE SPECIFICATION. NOTICE IS HEREBY GIVEN, THAT OTHER RIGHTS NOT GRANTED 
AS SET FORTH ABOVE, INCLUDING WITHOUT LIMITATION, RIGHTS OF THIRD PARTIES 
WHO DID NOT EXECUTE THE ABOVE LICENSES, MAY BE IMPLICATED BY THE 
IMPLEMENTATION OF OR COMPLIANCE WITH THIS SPECIFICATION. OCP IS NOT 
RESPONSIBLE FOR IDENTIFYING RIGHTS FOR WHICH A LICENSE MAY BE REQUIRED 
IN ORDER TO IMPLEMENT THIS SPECIFICATION.  THE ENTIRE RISK AS TO 
IMPLEMENTING OR OTHERWISE USING THE SPECIFICATION IS ASSUMED BY YOU. IN 
NO EVENT WILL OCP BE LIABLE TO YOU FOR ANY MONETARY DAMAGES WITH 
RESPECT TO ANY CLAIMS RELATED TO, OR ARISING OUT OF YOUR USE OF THIS 
SPECIFICATION, INCLUDING BUT NOT LIMITED TO ANY LIABILITY FOR LOST PROFITS 
OR ANY CONSEQUENTIAL, INCIDENTAL, INDIRECT, SPECIAL OR PUNITIVE DAMAGES 
OF ANY CHARACTER FROM ANY CAUSES OF ACTION OF ANY KIND WITH RESPECT TO 
THIS SPECIFICATION, WHETHER BASED ON BREACH OF CONTRACT, TORT 
(INCLUDING NEGLIGENCE), OR OTHERWISE, AND EVEN IF OCP HAS BEEN ADVISED OF 
THE POSSIBILITY OF SUCH DAMAGE. 
 
3.2. Acknowledgements 
The OCP-TAP LOF specification is the outcome of a collaborative effort of OCP-TAP members 
and contributors.  



Open Compute Project   •   TAP Large Oscillator Form-Factor (LOF) 
Date:  January 2023         Page 6 
 
OCP-TAP would like to acknowledge the following members and companies for their 
contributions  
 
• Kory Stone, Taitien  
• Ahmad Byagowi, Meta 
• Armando Julies Pinales, Meta 
• Julian St. James, Meta 
• Elad Wind, NVIDIA 
  



Open Compute Project   •   TAP Large Oscillator Form-Factor (LOF) 
Date:  January 2023         Page 7 
4. Compliance with OCP Tenets  
The LOF complies to the following OCP (4 out of 5) tenets.  
The ideals behind open sourcing stipulate that everyone benefits when we share and work 
together. Any open-source project is designed to promote sharing of design elements with peers 
and to help them understand and adopt those contributions.  
4.1. Openness 
The LOF takes a step into modularity of the OCP-TAP Time Card, by allowing a modular 
interchangeable Oscillators for holdover and precision to be easily provisioned into Time Cards.  
This standard modular form-factor allows for more vendors to drive their innovation and make 
time-aware data centers ubiquitous  
4.2. Efficiency  
With this modularity Time-Cards functionality can be designed and qualified separately from the 
holdover and precision and allow for parallel technological cycles to happen simultaneously. 
Technical improvements in the LOF do not mandate a change in the Time Card.  
4.3. Impact 
The LOF improves the time-to-market advantage of Oscillator such as the ability to introduce 
atomic clocks and more.  
4.4. Scale 
With the interest generated around Time Card standard, we expect multiple vendors to design 
and obtain product recognition (OCP Accepted™ or OCP Inspired™) for a thriving marketplace 
of Time-Cards, RCBs and LOFs at scale. 
 
  



Open Compute Project   •   TAP Large Oscillator Form-Factor (LOF) 
Date:  January 2023         Page 8 
5. Physical Specifications  
LOF module footprint, I/O and mechanical requirements are defined for interoperability with the 
OCP-TAP Time Card specification.  
 
The LOF consists of a 2 inch (50.8 mm) x 2 inch (50.8 mm) x 0.98 inch (25 mm) PCB.  
5.1. Labeling  
Labels will contain information about the part number and the serial number. The serial 
number indicates the initial time of manufacture. 
5.2. I/O  
The LOF contains the following I/O interfaces:  
PPS connection is a calibrating and disciplining feature that helps correct frequency and phase 
drifts (aging rate) from the primary clock to an externally applied PPS reference signal. 
5.3. Foot Print and Layout 
The LOF baseplate consists of 10 (of which 2 are optional) pins 
The screw holes (to be depicted) are optional as long as the locations are kept.  
Apply grounded keep-out areas for the screw holes  
 
 
Pin # Name Type Description 
1 NC/Tune Input Not connected or used for analog steering (tune) 
2 GND Power Power Return 
3 RF OUT Output Clock output, usually 10Mhz 
4 GND Power Power Return 
5 VCC Power Power Supply, 3v3, 5v or 12v (important to check) 
6 Lock Output Indicator of lock, goes high on lock, LVCMOS 
7 TXD Output UART TXD, LVCMOS 
8 RXD Input UART RXD, LVCMOS 
9 PPS In Input OPTIONAL 3.3v 
10 PPS Out Output OPTIONAL  3.3v 



Open Compute Project   •   TAP Large Oscillator Form-Factor (LOF) 
Date:  January 2023         Page 9 
5.3.1. Bottom View  
 
5.3.2. Side View 
 
 
6. Hardware Management 
We intentionally leave the hardware management of the LOF for the vendors to define and 
implement. This will cover programming of the ICs, diagnostics, etc.  
7. Version Table 
 
25mm 
23mm 
40.64mm 
40.64mm 
6.07mmm
mh 
3.0mm x 4 
1 
2 
3 
 4 
5 
10 9 8 7 6 
50.8mm 
50.8mm 



Open Compute Project   •   TAP Large Oscillator Form-Factor (LOF) 
Date:  January 2023         Page 10 
Date Version # Author Description 
January 23, 2023 0.1 OCP-TAP First draft 
    
8. References 
[1] OCP-TAP Time Card specification and all other related OCP-TAP specs can be found here 
https://github.com/opencomputeproject/Time-Appliance-Project    
 
  



Open Compute Project   •   TAP Large Oscillator Form-Factor (LOF) 
Date:  January 2023         Page 11 
Appendix A  - Checklist  for IC approval  
of this Specification (to be completed by contributor(s) of this Spec) 
Complete all the checklist items in the table with links to the section where it is described in this 
spec or an external document . 
Item  Status or Details Link to detailed explanation 
Is this contribution entered 
into the OCP Contribution 
Portal? 
Yes or No If no, please state reason. 
Was it approved in the OCP 
Contribution Portal? 
Yes or No If no, please state reason. 
Is there a Supplier(s) that is 
building a product based on 
this Spec? (Supplier must be 
an OCP Solution Provider) 
Yes or No List Supplier Name(s) 
Will Supplier(s) have the 
product available for 
GENERAL AVAILABILITY 
within 120 days? 
Yes or No If more time is required, 
please state the timeline and 
reason for extension request. 
 
Please have each Supplier fill 
out Appendix B.  
  



Open Compute Project   •   TAP Large Oscillator Form-Factor (LOF) 
Date:  January 2023         Page 12 
Appendix B-__ <supplier name>  - OCP Supplier Information and Hardware 
Product Recognition Checklist 
(to be provided by each  supplier seeking OCP recognition for a Hardware Product based on 
this specification)  
 
Company: 
Contact Info: 
 
Product Name: 
Product SKU#:  
Link to Product Landing Page: 
 
 
The following is needed for OCP hardware product recognition:  
 
For OCP Inspired™   
● All Suppliers must be a Silver, Gold or Platinum Member. 
● Declare product is 100% compliant with specification 
● Complete the OCP Inspired™ Product Recognition Checklist, which includes hardware 
management conformance checks and security profile. 
 
 
For OCP Accepted™  
● All Suppliers must be an OCP Member. All corporate membership levels are eligible.  
● Complete the OCP Accepted™ Product Recognition Checklist, which includes hardware 
management conformance checks, security profile and open system firmware 
conformance checks. 
● Submit a design package meeting OCP Hardware Design Guideline Contribution 
Checklist (if not already submitted by the contributor). If already submitted, declare the 
product is 100% compliant with the design package. 
● Submit a  firmware package including a firmware image, build scripts, documentation, 
test results and a tool that verifies modifications 
 
Please complete the OCP Inspired™ Product Recognition Submission Checklist or OCP 
Accepted™ Product Recognition Checklist and the following table. 
 
 
  
 
 
Item  Details Links 
Which product recognition? OCP Accepted™ or OCP 
Inspired™ 
Provide link for the 
appropriate Product Checklist 
If OCP Accepted™, who  Link to OCP Contribution 



Open Compute Project   •   TAP Large Oscillator Form-Factor (LOF) 
Date:  January 2023         Page 13 
provided the Design 
Package? 
Database 
Where can a potential 
adopter purchase the 
product? 
 
 Link to OCP Marketplace  
  



Open Compute Project   •   TAP Large Oscillator Form-Factor (LOF) 
Date:  January 2023         Page 14 
Appendix C -  Contribution Process FAQs 
 
As a contributor to a hardware specification, here are some questions that often come up. 
 
 
Q1.  What type of hardware specification am I contributing to OCP? Is it any of the below? 
a. base specification for a de-facto standard (new standard with no hardware 
product on the horizon) 
b. base specification for an intended physical <hardware product type> (product 
may be coming but within the next 1-2 years) 
c. modification of an existing specification (state which existing spec is being 
modified)  
i. either a complete revision update or  
ii. a minor version update 
d. design spec (based on an existing base specification) with more refined design 
details (product coming in 12-15months) 
e. a detailed specification for a <hardware product type> for a very specific product 
being available in 3-6months of approval of this Spec 
f. If none of the above, please contact OCP Staff for better direction. 
Q2.  How do I know if what I am contributing will be accepted by OCP? 
a. Before contributing any specifications, please contact either OCP Staff (Archna 
Haylock or Michael Schill) or the Project Lead for the Project that best represents 
your contribution. For example, if you are contributing a Server Specification, 
please contact one of the Server Project Leads. You can see all the Projects 
here.  
b. They will help you with your contribution and help you navigate the process. 
Q3.  What is the contribution process for my hardware spec? 
a. Follow the flow for your spec type here.  
b. This flow is subject to change so please check with the OCP Staff for more 
information or any questions. 
Q4. What if my spec is not developed yet and I want to collaborate with other companies? 
a. Please contact either OCP Staff (Archna Haylock or Michael Schill) or the Project 
Lead for the Project that best represents your contribution.  
b. They will help you find other collaborators and help you with the contribution 
process for a multi-party contribution. 
Q5. I have a question on the Contribution License Agreement.  
a. Please contact OCP Staff and we can help you with questions. 
Q6. Do I need to have a product in order to contribute a spec? 
a. Please see Q1. Some types of specs do not require an immediate product. Some 
do. Please work with the OCP Staff on better direction on your specification type. 